# BASEBOARD_FAB2 (Tioga Pass) — schematic netlist excerpt (pin names and nets, part order shuffled) for the footprints in the layout excerpt that follows; sources: Cadence DE-HDL packaged netlist, KiCad conversion of Wiwynn_Tioga_Pass_MB.brd

C5G80  CAP_A  22.0UF 4V 20% X6S  pkg 0603V  page 243 : A = PVDDQ_GHJ ; B = GND
R1L20  RES  10.0 1% CHIP  pkg 0402  page 155 : A = LED_POSTCODE_4 ; B = LED_POSTCODE_4_R
C5M8  CAP  100UF 4V 20% X5R  pkg 0805  page 220 : A = PVDDQ_DEF ; B = GND

(kicad_pcb
	(version 20260206)
	(generator "pcbnew")
	(generator_version "10.0")
	(general
		(thickness 1.6)
		(legacy_teardrops no)
	)
	(paper "A4")
	(title_block
		(title "Wiwynn_Tioga_Pass_MB.brd")
		(comment 1 "Tioga Pass / footprints 4745-4747 of 4770")
	)
	(layers
		(0 "F.Cu" signal "TOP")
		(4 "In1.Cu" signal "L2GND")
		(6 "In2.Cu" signal "L3")
		(8 "In3.Cu" signal "L4GND")
		(10 "In4.Cu" signal "L5")
		(12 "In5.Cu" signal "L6GND")
		(14 "In6.Cu" signal "L7VCC")
		(16 "In7.Cu" signal "L8VCC")
		(18 "In8.Cu" signal "L9GND")
		(20 "In9.Cu" signal "L10")
		(22 "In10.Cu" signal "L11GND")
		(24 "In11.Cu" signal "L12")
		(26 "In12.Cu" signal "L13GND")
		(2 "B.Cu" signal "BOTTOM")
		(9 "F.Adhes" user "F.Adhesive")
		(11 "B.Adhes" user "B.Adhesive")
		(13 "F.Paste" user "Package Geometry/Pastemask Top")
		(15 "B.Paste" user "Package Geometry/Pastemask Bottom")
		(5 "F.SilkS" user "Ref Des/Silkscreen Top")
		(7 "B.SilkS" user "Ref Des/Silkscreen Bottom")
		(1 "F.Mask" user "Board Geometry/Soldermask Top")
		(3 "B.Mask" user "Board Geometry/Soldermask Bottom")
		(17 "Dwgs.User" user "User.Drawings")
		(19 "Cmts.User" user "User.Comments")
		(21 "Eco1.User" user "User.Eco1")
		(23 "Eco2.User" user "User.Eco2")
		(25 "Edge.Cuts" user "Board Geometry/Outline")
		(27 "Margin" user)
		(31 "F.CrtYd" user "Package Geometry/Place Bound Top")
		(29 "B.CrtYd" user "Package Geometry/Place Bound Bottom")
		(35 "F.Fab" user "Ref Des/Assembly Top")
		(33 "B.Fab" user "Ref Des/Assembly Bottom")
	)
	(footprint ""
		(layer "B.Cu")
		(at 83.856068 -12.954 -90)
		(property "Reference" "C5G80"
			(at -1.14681 0.76708 0)
			(unlocked yes)
			(layer "B.SilkS")
			(effects
				(font
					(size 0.7874 0.5842)
					(thickness 0.1524)
				)
				(justify mirror)
			)
		)
		(property "Value" ""
			(at 0 0 90)
			(layer "B.Fab")
			(effects
				(font
					(size 1.27 1.27)
				)
				(justify mirror)
			)
		)
		(duplicate_pad_numbers_are_jumpers no)
		(fp_rect
			(start 0.4953 1.6002)
			(end -0.4953 -0.2032)
			(stroke
				(width 0)
				(type default)
			)
			(fill no)
			(layer "B.CrtYd")
		)
		(fp_line
			(start -0.4953 1.6002)
			(end 0.4953 1.6002)
			(stroke
				(width 0.1)
				(type default)
			)
			(layer "B.Fab")
		)
		(fp_line
			(start 0.4953 1.6002)
			(end 0.4953 -0.2032)
			(stroke
				(width 0.1)
				(type default)
			)
			(layer "B.Fab")
		)
		(fp_line
			(start -0.4953 -0.2032)
			(end -0.4953 1.6002)
			(stroke
				(width 0.1)
				(type default)
			)
			(layer "B.Fab")
		)
		(fp_line
			(start 0.4953 -0.2032)
			(end -0.4953 -0.2032)
			(stroke
				(width 0.1)
				(type default)
			)
			(layer "B.Fab")
		)
		(pad "1" smd rect
			(at 0 0 90)
			(size 0.762 0.889)
			(layers "B.Cu" "B.Mask" "B.Paste")
			(net "PVDDQ_GHJ")
		)
		(pad "2" smd rect
			(at 0 1.397 90)
			(size 0.762 0.889)
			(layers "B.Cu" "B.Mask" "B.Paste")
			(net "GND")
		)
		(zone
			(layer "B.Cu")
			(hatch none 0.5)
			(connect_pads
				(clearance 0)
			)
			(min_thickness 0.25)
			(keepout
				(tracks not_allowed)
				(vias allowed)
				(pads allowed)
				(copperpour not_allowed)
				(footprints allowed)
			)
			(placement
				(enabled no)
				(sheetname "")
			)
			(fill
				(thermal_gap 0.5)
				(thermal_bridge_width 0.5)
				(island_removal_mode 0)
			)
			(polygon
				(pts
					(xy 82.903568 -12.573) (xy 83.411568 -12.573) (xy 83.411568 -13.335) (xy 82.903568 -13.335)
				)
			)
		)
	)
	(footprint ""
		(layer "B.Cu")
		(at 489.65739 -145.288 90)
		(property "Reference" "R1L20"
			(at 0 0 90)
			(layer "B.SilkS")
			(hide yes)
			(effects
				(font
					(size 1.27 1.27)
				)
				(justify mirror)
			)
		)
		(property "Value" ""
			(at 0 0 90)
			(layer "B.Fab")
			(effects
				(font
					(size 1.27 1.27)
				)
				(justify mirror)
			)
		)
		(duplicate_pad_numbers_are_jumpers no)
		(fp_poly
			(pts
				(xy 0.2794 -0.1016) (xy -0.2794 -0.1016) (xy -0.2794 0.9906) (xy 0.2794 0.9906)
			)
			(stroke
				(width 0)
				(type default)
			)
			(fill no)
			(layer "B.CrtYd")
		)
		(fp_line
			(start 0.2794 -0.1016)
			(end 0.2794 0.9906)
			(stroke
				(width 0.1)
				(type default)
			)
			(layer "B.Fab")
		)
		(fp_line
			(start -0.2794 -0.1016)
			(end 0.2794 -0.1016)
			(stroke
				(width 0.1)
				(type default)
			)
			(layer "B.Fab")
		)
		(fp_line
			(start 0.2794 0.9906)
			(end -0.2794 0.9906)
			(stroke
				(width 0.1)
				(type default)
			)
			(layer "B.Fab")
		)
		(fp_line
			(start -0.2794 0.9906)
			(end -0.2794 -0.1016)
			(stroke
				(width 0.1)
				(type default)
			)
			(layer "B.Fab")
		)
		(pad "1" smd rect
			(at 0 0 270)
			(size 0.508 0.508)
			(layers "B.Cu" "B.Mask" "B.Paste")
			(net "LED_POSTCODE_4")
		)
		(pad "2" smd rect
			(at 0 0.889 270)
			(size 0.508 0.508)
			(layers "B.Cu" "B.Mask" "B.Paste")
			(net "LED_POSTCODE_4_R")
		)
		(zone
			(layer "B.Cu")
			(hatch none 0.5)
			(connect_pads
				(clearance 0)
			)
			(min_thickness 0.25)
			(keepout
				(tracks allowed)
				(vias not_allowed)
				(pads allowed)
				(copperpour not_allowed)
				(footprints allowed)
			)
			(placement
				(enabled no)
				(sheetname "")
			)
			(fill
				(thermal_gap 0.5)
				(thermal_bridge_width 0.5)
				(island_removal_mode 0)
			)
			(polygon
				(pts
					(xy 489.91139 -145.542) (xy 489.91139 -145.034) (xy 490.29239 -145.034) (xy 490.29239 -145.542)
				)
			)
		)
		(zone
			(layer "B.Cu")
			(hatch none 0.5)
			(connect_pads
				(clearance 0)
			)
			(min_thickness 0.25)
			(keepout
				(tracks not_allowed)
				(vias allowed)
				(pads allowed)
				(copperpour not_allowed)
				(footprints allowed)
			)
			(placement
				(enabled no)
				(sheetname "")
			)
			(fill
				(thermal_gap 0.5)
				(thermal_bridge_width 0.5)
				(island_removal_mode 0)
			)
			(polygon
				(pts
					(xy 490.29239 -145.542) (xy 490.29239 -145.034) (xy 489.91139 -145.034) (xy 489.91139 -145.542)
				)
			)
		)
	)
	(footprint ""
		(layer "B.Cu")
		(at 259.5372 -135.376412 90)
		(property "Reference" "C5M8"
			(at 0 0 90)
			(layer "B.SilkS")
			(hide yes)
			(effects
				(font
					(size 1.27 1.27)
				)
				(justify mirror)
			)
		)
		(property "Value" ""
			(at 0 0 90)
			(layer "B.Fab")
			(effects
				(font
					(size 1.27 1.27)
				)
				(justify mirror)
			)
		)
		(duplicate_pad_numbers_are_jumpers no)
		(fp_rect
			(start -0.7239 -0.2159)
			(end 0.7239 1.9939)
			(stroke
				(width 0)
				(type default)
			)
			(fill no)
			(layer "B.CrtYd")
		)
		(fp_line
			(start 0.7239 -0.2159)
			(end 0.7239 1.9939)
			(stroke
				(width 0.1)
				(type default)
			)
			(layer "B.Fab")
		)
		(fp_line
			(start -0.7239 -0.2159)
			(end 0.7239 -0.2159)
			(stroke
				(width 0.1)
				(type default)
			)
			(layer "B.Fab")
		)
		(fp_line
			(start 0.7239 1.9939)
			(end -0.7239 1.9939)
			(stroke
				(width 0.1)
				(type default)
			)
			(layer "B.Fab")
		)
		(fp_line
			(start -0.7239 1.9939)
			(end -0.7239 -0.2159)
			(stroke
				(width 0.1)
				(type default)
			)
			(layer "B.Fab")
		)
		(pad "1" smd rect
			(at 0 0 270)
			(size 1.27 1.016)
			(layers "B.Cu" "B.Mask" "B.Paste")
			(net "PVDDQ_DEF")
		)
		(pad "2" smd rect
			(at 0 1.778 270)
			(size 1.27 1.016)
			(layers "B.Cu" "B.Mask" "B.Paste")
			(net "GND")
		)
		(zone
			(layer "B.Cu")
			(hatch none 0.5)
			(connect_pads
				(clearance 0)
			)
			(min_thickness 0.25)
			(keepout
				(tracks not_allowed)
				(vias allowed)
				(pads allowed)
				(copperpour not_allowed)
				(footprints allowed)
			)
			(placement
				(enabled no)
				(sheetname "")
			)
			(fill
				(thermal_gap 0.5)
				(thermal_bridge_width 0.5)
				(island_removal_mode 0)
			)
			(polygon
				(pts
					(xy 260.0452 -134.741412) (xy 260.8072 -134.741412) (xy 260.8072 -136.011412) (xy 260.0452 -136.011412)
				)
			)
		)
	)
)
